(kicad_pcb
	(version 20221018)
	(generator pcbnew)
	(general
    (thickness 1.562)
  )
	(paper "A4")
	(title_block
    (title "Thunderbolt PCIe Adaper")
    (date "2024-07-09")
    (rev "1.0.3")
    (comment 1 "www.antmicro.com")
    (comment 2 "Antmicro Ltd.")
		(comment 9 "footprints 168-176 of 271")
	)
	(layers
    (0 "F.Cu" signal)
    (1 "In1.Cu" signal)
    (2 "In2.Cu" signal)
    (3 "In3.Cu" signal)
    (4 "In4.Cu" signal)
    (31 "B.Cu" signal)
    (32 "B.Adhes" user "B.Adhesive")
    (33 "F.Adhes" user "F.Adhesive")
    (34 "B.Paste" user)
    (35 "F.Paste" user)
    (36 "B.SilkS" user "B.Silkscreen")
    (37 "F.SilkS" user "F.Silkscreen")
    (38 "B.Mask" user)
    (39 "F.Mask" user)
    (40 "Dwgs.User" user "User.Drawings")
    (41 "Cmts.User" user "User.Comments")
    (42 "Eco1.User" user "User.Eco1")
    (43 "Eco2.User" user "User.Eco2")
    (44 "Edge.Cuts" user)
    (45 "Margin" user)
    (46 "B.CrtYd" user "B.Courtyard")
    (47 "F.CrtYd" user "F.Courtyard")
    (48 "B.Fab" user)
    (49 "F.Fab" user)
  )
	(footprint "antmicro-footprints:C_0402_1005Metric" (layer "B.Cu")
    (at 122.998 75.17)
    (descr "Capacitor SMD 0402")
    (tags "capacitor SMD 0402")
    (property "Author" "Antmicro")
    (property "Dielectric" "C0G")
    (property "License" "Apache-2.0")
    (property "MPN" "GCM1555C1H100GA16D")
    (property "Manufacturer" "Murata")
    (property "Sheetfile" "tb.kicad_sch")
    (property "Sheetname" "TB Controller")
    (property "Val" "10p")
    (property "Voltage" "50V")
    (property "ki_description" "SMD Multilayer Ceramic Capacitor, 10 pF, 50 V, 0402 [1005 Metric], ± 2%, C0G / NP0, GCM")
    (property "ki_keywords" "0402, SMT, CAPACITOR, PASSIVE")
    (attr smd)
    (fp_text reference "C113" (at 1.208 -0.621 180) (layer "B.SilkS")
        (effects (font (size 0.7 0.7) (thickness 0.15)) (justify left bottom mirror))
    )
    (fp_text value "C_10p_0402" (at -1.022927 -2.155213 180) (layer "B.Fab")
        (effects (font (size 0.7 0.7) (thickness 0.15)) (justify left bottom mirror))
    )
    (fp_text user "Author: Antmicro" (at -0.939 -3.399 180) (layer "B.Fab") hide
        (effects (font (size 0.7 0.7) (thickness 0.15)) (justify left bottom mirror))
    )
    (fp_text user "License: Apache-2.0" (at -0.939 -5.799 180) (layer "B.Fab") hide
        (effects (font (size 0.7 0.7) (thickness 0.15)) (justify left bottom mirror))
    )
    (fp_text user "${REFERENCE}" (at -0.939 -4.599 180) (layer "B.Fab") hide
        (effects (font (size 0.7 0.7) (thickness 0.15)) (justify left bottom mirror))
    )
    (fp_rect (start -0.925 0.47) (end 0.925 -0.47)
      (stroke (width 0.05) (type default)) (fill none) (layer "B.CrtYd"))
    (fp_line (start -0.494 -0.248) (end -0.494 0.25)
      (stroke (width 0.15) (type solid)) (layer "B.Fab"))
    (fp_line (start -0.494 0.25) (end 0.504 0.25)
      (stroke (width 0.15) (type solid)) (layer "B.Fab"))
    (fp_line (start 0.504 -0.248) (end -0.494 -0.248)
      (stroke (width 0.15) (type solid)) (layer "B.Fab"))
    (fp_line (start 0.504 0.25) (end 0.504 -0.248)
      (stroke (width 0.15) (type solid)) (layer "B.Fab"))
    (pad "1" smd roundrect (at -0.48 0) (size 0.59 0.64) (layers "B.Cu" "B.Paste" "B.Mask") (roundrect_rratio 0.25)
      (net 1 "GND") (pintype "passive"))
    (pad "2" smd roundrect (at 0.48 0) (size 0.59 0.64) (layers "B.Cu" "B.Paste" "B.Mask") (roundrect_rratio 0.25)
      (net 115 "Net-(U6-XOUT)") (pintype "passive"))
  )
	(footprint "antmicro-footprints:R_0402_1005Metric" (layer "B.Cu")
    (at 161.41 61.97)
    (descr "Resistor SMD 0402")
    (tags "resistor SMD 0402")
    (property "Author" "Antmicro")
    (property "License" "Apache-2.0")
    (property "MPN" "CR0402-FX-1002GLF")
    (property "Manufacturer" "Bourns")
    (property "Sheetfile" "power.kicad_sch")
    (property "Sheetname" "Power")
    (property "Tolerance" "1%")
    (property "Val" "10k")
    (property "ki_description" "SMD Chip Resistor, 10 kohm, ± 1%, 62.5 mW, 0402 [1005 Metric], Thick Film, General Purpose")
    (property "ki_keywords" "0402, SMT, RESISTOR, PASSIVE")
    (attr smd)
    (fp_text reference "R39" (at 3.182 0.387 180) (layer "B.SilkS")
        (effects (font (size 0.7 0.7) (thickness 0.15)) (justify left bottom mirror))
    )
    (fp_text value "R_10k_0402" (at -1.011843 -1.772047 180) (layer "B.Fab")
        (effects (font (size 0.7 0.7) (thickness 0.15)) (justify left bottom mirror))
    )
    (fp_text user "Author: Antmicro" (at -0.95 -4.169 180) (layer "B.Fab") hide
        (effects (font (size 0.7 0.7) (thickness 0.15)) (justify left bottom mirror))
    )
    (fp_text user "${REFERENCE}" (at -0.95 -3.168 180) (layer "B.Fab") hide
        (effects (font (size 0.7 0.7) (thickness 0.15)) (justify left bottom mirror))
    )
    (fp_text user "License: Apache-2.0" (at -0.95 -5.169 180) (layer "B.Fab") hide
        (effects (font (size 0.7 0.7) (thickness 0.15)) (justify left bottom mirror))
    )
    (fp_rect (start -0.925 0.47) (end 0.925 -0.47)
      (stroke (width 0.05) (type default)) (fill none) (layer "B.CrtYd"))
    (fp_rect (start -0.5 0.25) (end 0.5 -0.25)
      (stroke (width 0.15) (type solid)) (fill none) (layer "B.Fab"))
    (pad "1" smd roundrect (at -0.48 0) (size 0.59 0.64) (layers "B.Cu" "B.Paste" "B.Mask") (roundrect_rratio 0.25)
      (net 62 "RESET_N") (pintype "passive"))
    (pad "2" smd roundrect (at 0.48 0) (size 0.59 0.64) (layers "B.Cu" "B.Paste" "B.Mask") (roundrect_rratio 0.25)
      (net 9 "/Power/TPS_3V3") (pintype "passive"))
  )
	(footprint "antmicro-footprints:C_0402_1005Metric" (layer "B.Cu")
    (at 128.48 80.34 -90)
    (descr "Capacitor SMD 0402")
    (tags "capacitor SMD 0402")
    (property "Author" "Antmicro")
    (property "Dielectric" "")
    (property "License" "Apache-2.0")
    (property "MPN" "C1005X6S1A105K050BC")
    (property "Manufacturer" "TDK")
    (property "Sheetfile" "tb-power.kicad_sch")
    (property "Sheetname" "Thunderbolt Controller - Power")
    (property "Val" "1u")
    (property "Voltage" "")
    (property "ki_description" "SMD Multilayer Ceramic Capacitor, 1 µF, 10 V, 0402 [1005 Metric], ± 10%, X6S, C")
    (property "ki_keywords" "0402, SMT, CAPACITOR, PASSIVE, CERAMIC, MLCC")
    (attr smd)
    (fp_text reference "C94" (at -0.965 2.537 90) (layer "B.SilkS")
        (effects (font (size 0.7 0.7) (thickness 0.15)) (justify left bottom mirror))
    )
    (fp_text value "C_1u_0402" (at -1.022927 -2.155213 90) (layer "B.Fab")
        (effects (font (size 0.7 0.7) (thickness 0.15)) (justify left bottom mirror))
    )
    (fp_text user "${REFERENCE}" (at -0.939 -4.599 90) (layer "B.Fab") hide
        (effects (font (size 0.7 0.7) (thickness 0.15)) (justify left bottom mirror))
    )
    (fp_text user "Author: Antmicro" (at -0.939 -3.399 90) (layer "B.Fab") hide
        (effects (font (size 0.7 0.7) (thickness 0.15)) (justify left bottom mirror))
    )
    (fp_text user "License: Apache-2.0" (at -0.939 -5.799 90) (layer "B.Fab") hide
        (effects (font (size 0.7 0.7) (thickness 0.15)) (justify left bottom mirror))
    )
    (fp_rect (start -0.925 0.47) (end 0.925 -0.47)
      (stroke (width 0.05) (type default)) (fill none) (layer "B.CrtYd"))
    (fp_line (start -0.494 -0.248) (end -0.494 0.25)
      (stroke (width 0.15) (type solid)) (layer "B.Fab"))
    (fp_line (start -0.494 0.25) (end 0.504 0.25)
      (stroke (width 0.15) (type solid)) (layer "B.Fab"))
    (fp_line (start 0.504 -0.248) (end -0.494 -0.248)
      (stroke (width 0.15) (type solid)) (layer "B.Fab"))
    (fp_line (start 0.504 0.25) (end 0.504 -0.248)
      (stroke (width 0.15) (type solid)) (layer "B.Fab"))
    (pad "1" smd roundrect (at -0.48 0 270) (size 0.59 0.64) (layers "B.Cu" "B.Paste" "B.Mask") (roundrect_rratio 0.25)
      (net 1 "GND") (pintype "passive"))
    (pad "2" smd roundrect (at 0.48 0 270) (size 0.59 0.64) (layers "B.Cu" "B.Paste" "B.Mask") (roundrect_rratio 0.25)
      (net 114 "Net-(U4A-VCC3P3_S0)") (pintype "passive"))
  )
	(footprint "antmicro-footprints:R_0402_1005Metric" (layer "B.Cu")
    (at 128.19 76.83 180)
    (descr "Resistor SMD 0402")
    (tags "resistor SMD 0402")
    (property "Author" "Antmicro")
    (property "License" "Apache-2.0")
    (property "MPN" "CR0402-FX-1000GLF")
    (property "Manufacturer" "Bourns")
    (property "Sheetfile" "tb.kicad_sch")
    (property "Sheetname" "TB Controller")
    (property "Tolerance" "1%")
    (property "Val" "100R")
    (property "ki_description" "SMD Chip Resistor, 100 ohm, ± 1%, 62.5 mW, 0402 [1005 Metric], Thick Film, General Purpose")
    (property "ki_keywords" "0402, SMT, RESISTOR, PASSIVE")
    (attr smd)
    (fp_text reference "R89" (at 0.936 -0.386) (layer "B.SilkS")
        (effects (font (size 0.7 0.7) (thickness 0.15)) (justify left bottom mirror))
    )
    (fp_text value "R_100R_0402" (at -1.011843 -1.772047) (layer "B.Fab")
        (effects (font (size 0.7 0.7) (thickness 0.15)) (justify left bottom mirror))
    )
    (fp_text user "${REFERENCE}" (at -0.95 -3.168) (layer "B.Fab") hide
        (effects (font (size 0.7 0.7) (thickness 0.15)) (justify left bottom mirror))
    )
    (fp_text user "Author: Antmicro" (at -0.95 -4.169) (layer "B.Fab") hide
        (effects (font (size 0.7 0.7) (thickness 0.15)) (justify left bottom mirror))
    )
    (fp_text user "License: Apache-2.0" (at -0.95 -5.169) (layer "B.Fab") hide
        (effects (font (size 0.7 0.7) (thickness 0.15)) (justify left bottom mirror))
    )
    (fp_rect (start -0.925 0.47) (end 0.925 -0.47)
      (stroke (width 0.05) (type default)) (fill none) (layer "B.CrtYd"))
    (fp_rect (start -0.5 0.25) (end 0.5 -0.25)
      (stroke (width 0.15) (type solid)) (fill none) (layer "B.Fab"))
    (pad "1" smd roundrect (at -0.48 0 180) (size 0.59 0.64) (layers "B.Cu" "B.Paste" "B.Mask") (roundrect_rratio 0.25)
      (net 204 "Net-(U4D-TEST_PWR_GOOD)") (pintype "passive"))
    (pad "2" smd roundrect (at 0.48 0 180) (size 0.59 0.64) (layers "B.Cu" "B.Paste" "B.Mask") (roundrect_rratio 0.25)
      (net 1 "GND") (pintype "passive"))
  )
	(footprint "antmicro-footprints:R_0402_1005Metric" (layer "B.Cu")
    (at 151.41 61.97)
    (descr "Resistor SMD 0402")
    (tags "resistor SMD 0402")
    (property "Author" "Antmicro")
    (property "License" "Apache-2.0")
    (property "MPN" "CR0402-FX-2201GLF")
    (property "Manufacturer" "Bourns")
    (property "Sheetfile" "power.kicad_sch")
    (property "Sheetname" "Power")
    (property "Tolerance" "1%")
    (property "Val" "2k2")
    (property "ki_description" "SMD Chip Resistor, 2.2 kohm, ± 1%, 62.5 mW, 0402 [1005 Metric], Thick Film, General Purpose")
    (property "ki_keywords" "0402, SMT, RESISTOR, PASSIVE")
    (attr smd)
    (fp_text reference "R5" (at -0.915 0.482 180) (layer "B.SilkS")
        (effects (font (size 0.7 0.7) (thickness 0.15)) (justify left bottom mirror))
    )
    (fp_text value "R_2k2_0402" (at -1.011843 -1.772047 180) (layer "B.Fab")
        (effects (font (size 0.7 0.7) (thickness 0.15)) (justify left bottom mirror))
    )
    (fp_text user "Author: Antmicro" (at -0.95 -4.169 180) (layer "B.Fab") hide
        (effects (font (size 0.7 0.7) (thickness 0.15)) (justify left bottom mirror))
    )
    (fp_text user "License: Apache-2.0" (at -0.95 -5.169 180) (layer "B.Fab") hide
        (effects (font (size 0.7 0.7) (thickness 0.15)) (justify left bottom mirror))
    )
    (fp_text user "${REFERENCE}" (at -0.95 -3.168 180) (layer "B.Fab") hide
        (effects (font (size 0.7 0.7) (thickness 0.15)) (justify left bottom mirror))
    )
    (fp_rect (start -0.925 0.47) (end 0.925 -0.47)
      (stroke (width 0.05) (type default)) (fill none) (layer "B.CrtYd"))
    (fp_rect (start -0.5 0.25) (end 0.5 -0.25)
      (stroke (width 0.15) (type solid)) (fill none) (layer "B.Fab"))
    (pad "1" smd roundrect (at -0.48 0) (size 0.59 0.64) (layers "B.Cu" "B.Paste" "B.Mask") (roundrect_rratio 0.25)
      (net 59 "I2C1_SDA") (pintype "passive"))
    (pad "2" smd roundrect (at 0.48 0) (size 0.59 0.64) (layers "B.Cu" "B.Paste" "B.Mask") (roundrect_rratio 0.25)
      (net 2 "3V3_SYS") (pintype "passive"))
  )
	(footprint "antmicro-footprints:R_0402_1005Metric" (layer "B.Cu")
    (at 135.115 62.93)
    (descr "Resistor SMD 0402")
    (tags "resistor SMD 0402")
    (property "Author" "Antmicro")
    (property "License" "Apache-2.0")
    (property "MPN" "CR0402-FX-3301GLF")
    (property "Manufacturer" "Bourns")
    (property "Sheetfile" "tb.kicad_sch")
    (property "Sheetname" "TB Controller")
    (property "Tolerance" "1%")
    (property "Val" "3k3")
    (property "ki_description" "SMD Chip Resistor, 3.3 kohm, ± 1%, 63 mW, 0402 [1005 Metric], Thick Film, General Purpose")
    (property "ki_keywords" "0402, SMT, RESISTOR, PASSIVE")
    (attr smd)
    (fp_text reference "R51" (at -1.003 0.443 180) (layer "B.SilkS")
        (effects (font (size 0.7 0.7) (thickness 0.15)) (justify left bottom mirror))
    )
    (fp_text value "R_3k3_0402" (at -1.011843 -1.772047 180) (layer "B.Fab")
        (effects (font (size 0.7 0.7) (thickness 0.15)) (justify left bottom mirror))
    )
    (fp_text user "Author: Antmicro" (at -0.95 -4.169 180) (layer "B.Fab") hide
        (effects (font (size 0.7 0.7) (thickness 0.15)) (justify left bottom mirror))
    )
    (fp_text user "${REFERENCE}" (at -0.95 -3.168 180) (layer "B.Fab") hide
        (effects (font (size 0.7 0.7) (thickness 0.15)) (justify left bottom mirror))
    )
    (fp_text user "License: Apache-2.0" (at -0.95 -5.169 180) (layer "B.Fab") hide
        (effects (font (size 0.7 0.7) (thickness 0.15)) (justify left bottom mirror))
    )
    (fp_rect (start -0.925 0.47) (end 0.925 -0.47)
      (stroke (width 0.05) (type default)) (fill none) (layer "B.CrtYd"))
    (fp_rect (start -0.5 0.25) (end 0.5 -0.25)
      (stroke (width 0.15) (type solid)) (fill none) (layer "B.Fab"))
    (pad "1" smd roundrect (at -0.48 0) (size 0.59 0.64) (layers "B.Cu" "B.Paste" "B.Mask") (roundrect_rratio 0.25)
      (net 64 "/TB Controller/FLASH_WP") (pintype "passive"))
    (pad "2" smd roundrect (at 0.48 0) (size 0.59 0.64) (layers "B.Cu" "B.Paste" "B.Mask") (roundrect_rratio 0.25)
      (net 2 "3V3_SYS") (pintype "passive"))
  )
	(footprint "antmicro-footprints:R_0402_1005Metric" (layer "B.Cu")
    (at 115.23 91.63 90)
    (descr "Resistor SMD 0402")
    (tags "resistor SMD 0402")
    (property "Author" "Antmicro")
    (property "License" "Apache-2.0")
    (property "MPN" "CR0402-FX-1003GLF")
    (property "Manufacturer" "Bourns")
    (property "Sheetfile" "power.kicad_sch")
    (property "Sheetname" "Power")
    (property "Tolerance" "1%")
    (property "Val" "100k")
    (property "ki_description" "SMD Chip Resistor, 100 kohm, ± 1%, 62.5 mW, 0402 [1005 Metric], Thick Film, General Purpose")
    (property "ki_keywords" "0402, SMT, RESISTOR, PASSIVE")
    (attr smd)
    (fp_text reference "R96" (at 1.079 3.515 270) (layer "B.SilkS")
        (effects (font (size 0.7 0.7) (thickness 0.15)) (justify left bottom mirror))
    )
    (fp_text value "R_100k_0402" (at -1.011843 -1.772047 270) (layer "B.Fab")
        (effects (font (size 0.7 0.7) (thickness 0.15)) (justify left bottom mirror))
    )
    (fp_text user "Author: Antmicro" (at -0.95 -4.169 270) (layer "B.Fab") hide
        (effects (font (size 0.7 0.7) (thickness 0.15)) (justify left bottom mirror))
    )
    (fp_text user "License: Apache-2.0" (at -0.95 -5.169 270) (layer "B.Fab") hide
        (effects (font (size 0.7 0.7) (thickness 0.15)) (justify left bottom mirror))
    )
    (fp_text user "${REFERENCE}" (at -0.95 -3.168 270) (layer "B.Fab") hide
        (effects (font (size 0.7 0.7) (thickness 0.15)) (justify left bottom mirror))
    )
    (fp_rect (start -0.925 0.47) (end 0.925 -0.47)
      (stroke (width 0.05) (type default)) (fill none) (layer "B.CrtYd"))
    (fp_rect (start -0.5 0.25) (end 0.5 -0.25)
      (stroke (width 0.15) (type solid)) (fill none) (layer "B.Fab"))
    (pad "1" smd roundrect (at -0.48 0 90) (size 0.59 0.64) (layers "B.Cu" "B.Paste" "B.Mask") (roundrect_rratio 0.25)
      (net 1 "GND") (pintype "passive"))
    (pad "2" smd roundrect (at 0.48 0 90) (size 0.59 0.64) (layers "B.Cu" "B.Paste" "B.Mask") (roundrect_rratio 0.25)
      (net 145 "Net-(Q4-BIAS)") (pintype "passive"))
  )
	(footprint "antmicro-footprints:R_0402_1005Metric" (layer "B.Cu")
    (at 135.175 66.82 -90)
    (descr "Resistor SMD 0402")
    (tags "resistor SMD 0402")
    (property "Author" "Antmicro")
    (property "License" "Apache-2.0")
    (property "MPN" "CR0402-FX-1002GLF")
    (property "Manufacturer" "Bourns")
    (property "Sheetfile" "tb.kicad_sch")
    (property "Sheetname" "TB Controller")
    (property "Tolerance" "1%")
    (property "Val" "10k")
    (property "ki_description" "SMD Chip Resistor, 10 kohm, ± 1%, 62.5 mW, 0402 [1005 Metric], Thick Film, General Purpose")
    (property "ki_keywords" "0402, SMT, RESISTOR, PASSIVE")
    (attr smd)
    (fp_text reference "R65" (at -3.066 -0.325 90) (layer "B.SilkS")
        (effects (font (size 0.7 0.7) (thickness 0.15)) (justify left bottom mirror))
    )
    (fp_text value "R_10k_0402" (at -1.011843 -1.772047 90) (layer "B.Fab")
        (effects (font (size 0.7 0.7) (thickness 0.15)) (justify left bottom mirror))
    )
    (fp_text user "License: Apache-2.0" (at -0.95 -5.169 90) (layer "B.Fab") hide
        (effects (font (size 0.7 0.7) (thickness 0.15)) (justify left bottom mirror))
    )
    (fp_text user "Author: Antmicro" (at -0.95 -4.169 90) (layer "B.Fab") hide
        (effects (font (size 0.7 0.7) (thickness 0.15)) (justify left bottom mirror))
    )
    (fp_text user "${REFERENCE}" (at -0.95 -3.168 90) (layer "B.Fab") hide
        (effects (font (size 0.7 0.7) (thickness 0.15)) (justify left bottom mirror))
    )
    (fp_rect (start -0.925 0.47) (end 0.925 -0.47)
      (stroke (width 0.05) (type default)) (fill none) (layer "B.CrtYd"))
    (fp_rect (start -0.5 0.25) (end 0.5 -0.25)
      (stroke (width 0.15) (type solid)) (fill none) (layer "B.Fab"))
    (pad "1" smd roundrect (at -0.48 0 270) (size 0.59 0.64) (layers "B.Cu" "B.Paste" "B.Mask") (roundrect_rratio 0.25)
      (net 2 "3V3_SYS") (pintype "passive"))
    (pad "2" smd roundrect (at 0.48 0 270) (size 0.59 0.64) (layers "B.Cu" "B.Paste" "B.Mask") (roundrect_rratio 0.25)
      (net 179 "Net-(U4D-TMS)") (pintype "passive"))
  )
	(footprint "antmicro-footprints:R_0402_1005Metric" (layer "B.Cu")
    (at 130.05 66.82 -90)
    (descr "Resistor SMD 0402")
    (tags "resistor SMD 0402")
    (property "Author" "Antmicro")
    (property "License" "Apache-2.0")
    (property "MPN" "CR0402-FX-1003GLF")
    (property "Manufacturer" "Bourns")
    (property "Sheetfile" "tb.kicad_sch")
    (property "Sheetname" "TB Controller")
    (property "Tolerance" "1%")
    (property "Val" "100k")
    (property "ki_description" "SMD Chip Resistor, 100 kohm, ± 1%, 62.5 mW, 0402 [1005 Metric], Thick Film, General Purpose")
    (property "ki_keywords" "0402, SMT, RESISTOR, PASSIVE")
    (attr smd)
    (fp_text reference "R60" (at -3.066 -0.325 90) (layer "B.SilkS")
        (effects (font (size 0.7 0.7) (thickness 0.15)) (justify left bottom mirror))
    )
    (fp_text value "R_100k_0402" (at -1.011843 -1.772047 90) (layer "B.Fab")
        (effects (font (size 0.7 0.7) (thickness 0.15)) (justify left bottom mirror))
    )
    (fp_text user "Author: Antmicro" (at -0.95 -4.169 90) (layer "B.Fab") hide
        (effects (font (size 0.7 0.7) (thickness 0.15)) (justify left bottom mirror))
    )
    (fp_text user "License: Apache-2.0" (at -0.95 -5.169 90) (layer "B.Fab") hide
        (effects (font (size 0.7 0.7) (thickness 0.15)) (justify left bottom mirror))
    )
    (fp_text user "${REFERENCE}" (at -0.95 -3.168 90) (layer "B.Fab") hide
        (effects (font (size 0.7 0.7) (thickness 0.15)) (justify left bottom mirror))
    )
    (fp_rect (start -0.925 0.47) (end 0.925 -0.47)
      (stroke (width 0.05) (type default)) (fill none) (layer "B.CrtYd"))
    (fp_rect (start -0.5 0.25) (end 0.5 -0.25)
      (stroke (width 0.15) (type solid)) (fill none) (layer "B.Fab"))
    (pad "1" smd roundrect (at -0.48 0 270) (size 0.59 0.64) (layers "B.Cu" "B.Paste" "B.Mask") (roundrect_rratio 0.25)
      (net 1 "GND") (pintype "passive"))
    (pad "2" smd roundrect (at 0.48 0 270) (size 0.59 0.64) (layers "B.Cu" "B.Paste" "B.Mask") (roundrect_rratio 0.25)
      (net 174 "Net-(U4C-DPSNK1_HPD)") (pintype "passive"))
  )
)
